(kicad_pcb
	(version 20260206)
	(generator "pcbnew")
	(generator_version "10.0")
	(general
		(thickness 1.6)
		(legacy_teardrops no)
	)
	(paper "A4")
	(title_block
		(title "Wiwynn_Tioga_Pass_MB.brd")
		(comment 1 "Tioga Pass / footprint 830 of 4770 (J1A1), pads 124-243 of 291")
	)
	(layers
		(0 "F.Cu" signal "TOP")
		(4 "In1.Cu" signal "L2GND")
		(6 "In2.Cu" signal "L3")
		(8 "In3.Cu" signal "L4GND")
		(10 "In4.Cu" signal "L5")
		(12 "In5.Cu" signal "L6GND")
		(14 "In6.Cu" signal "L7VCC")
		(16 "In7.Cu" signal "L8VCC")
		(18 "In8.Cu" signal "L9GND")
		(20 "In9.Cu" signal "L10")
		(22 "In10.Cu" signal "L11GND")
		(24 "In11.Cu" signal "L12")
		(26 "In12.Cu" signal "L13GND")
		(2 "B.Cu" signal "BOTTOM")
		(9 "F.Adhes" user "F.Adhesive")
		(11 "B.Adhes" user "B.Adhesive")
		(13 "F.Paste" user "Package Geometry/Pastemask Top")
		(15 "B.Paste" user "Package Geometry/Pastemask Bottom")
		(5 "F.SilkS" user "Ref Des/Silkscreen Top")
		(7 "B.SilkS" user "Ref Des/Silkscreen Bottom")
		(1 "F.Mask" user "Board Geometry/Soldermask Top")
		(3 "B.Mask" user "Board Geometry/Soldermask Bottom")
		(17 "Dwgs.User" user "User.Drawings")
		(19 "Cmts.User" user "User.Comments")
		(21 "Eco1.User" user "User.Eco1")
		(23 "Eco2.User" user "User.Eco2")
		(25 "Edge.Cuts" user "Board Geometry/Outline")
		(27 "Margin" user)
		(31 "F.CrtYd" user "Package Geometry/Place Bound Top")
		(29 "B.CrtYd" user "Package Geometry/Place Bound Bottom")
		(35 "F.Fab" user "Ref Des/Assembly Top")
		(33 "B.Fab" user "Ref Des/Assembly Bottom")
	)
	(footprint ""
		(layer "F.Cu")
		(at 29.699458 -152.273 90)
		(property "Reference" "J1A1"
			(at -2.572512 42.563542 0)
			(unlocked yes)
			(layer "F.SilkS")
			(effects
				(font
					(size 0.7874 0.5842)
					(thickness 0.1524)
				)
				(justify left)
			)
		)
		(property "Value" ""
			(at 0 0 90)
			(layer "F.Fab")
			(effects
				(font
					(size 1.27 1.27)
				)
			)
		)
		(duplicate_pad_numbers_are_jumpers no)
		(pad "121" smd rect
			(at 0 107.100116 90)
			(size 1.8034 0.508)
			(layers "F.Cu" "F.Mask" "F.Paste")
			(net "M_M_DQS_DP<15>")
		)
		(pad "122" smd rect
			(at 0 107.95 90)
			(size 1.8034 0.508)
			(layers "F.Cu" "F.Mask" "F.Paste")
			(net "M_M_DQS_DN<15>")
		)
		(pad "123" smd rect
			(at 0 108.799884 90)
			(size 1.8034 0.508)
			(layers "F.Cu" "F.Mask" "F.Paste")
			(net "GND")
		)
		(pad "124" smd rect
			(at 0 109.650022 90)
			(size 1.8034 0.508)
			(layers "F.Cu" "F.Mask" "F.Paste")
			(net "M_M_DQ<55>")
		)
		(pad "125" smd rect
			(at 0 110.499906 90)
			(size 1.8034 0.508)
			(layers "F.Cu" "F.Mask" "F.Paste")
			(net "GND")
		)
		(pad "126" smd rect
			(at 0 111.350044 90)
			(size 1.8034 0.508)
			(layers "F.Cu" "F.Mask" "F.Paste")
			(net "M_M_DQ<51>")
		)
		(pad "127" smd rect
			(at 0 112.199928 90)
			(size 1.8034 0.508)
			(layers "F.Cu" "F.Mask" "F.Paste")
			(net "GND")
		)
		(pad "128" smd rect
			(at 0 113.050066 90)
			(size 1.8034 0.508)
			(layers "F.Cu" "F.Mask" "F.Paste")
			(net "M_M_DQ<61>")
		)
		(pad "129" smd rect
			(at 0 113.89995 90)
			(size 1.8034 0.508)
			(layers "F.Cu" "F.Mask" "F.Paste")
			(net "GND")
		)
		(pad "130" smd rect
			(at 0 114.750088 90)
			(size 1.8034 0.508)
			(layers "F.Cu" "F.Mask" "F.Paste")
			(net "M_M_DQ<57>")
		)
		(pad "131" smd rect
			(at 0 115.599972 90)
			(size 1.8034 0.508)
			(layers "F.Cu" "F.Mask" "F.Paste")
			(net "GND")
		)
		(pad "132" smd rect
			(at 0 116.45011 90)
			(size 1.8034 0.508)
			(layers "F.Cu" "F.Mask" "F.Paste")
			(net "M_M_DQS_DP<16>")
		)
		(pad "133" smd rect
			(at 0 117.299994 90)
			(size 1.8034 0.508)
			(layers "F.Cu" "F.Mask" "F.Paste")
			(net "M_M_DQS_DN<16>")
		)
		(pad "134" smd rect
			(at 0 118.149878 90)
			(size 1.8034 0.508)
			(layers "F.Cu" "F.Mask" "F.Paste")
			(net "GND")
		)
		(pad "135" smd rect
			(at 0 119.000016 90)
			(size 1.8034 0.508)
			(layers "F.Cu" "F.Mask" "F.Paste")
			(net "M_M_DQ<63>")
		)
		(pad "136" smd rect
			(at 0 119.8499 90)
			(size 1.8034 0.508)
			(layers "F.Cu" "F.Mask" "F.Paste")
			(net "GND")
		)
		(pad "137" smd rect
			(at 0 120.700038 90)
			(size 1.8034 0.508)
			(layers "F.Cu" "F.Mask" "F.Paste")
			(net "M_M_DQ<59>")
		)
		(pad "138" smd rect
			(at 0 121.549922 90)
			(size 1.8034 0.508)
			(layers "F.Cu" "F.Mask" "F.Paste")
			(net "GND")
		)
		(pad "139" smd rect
			(at 0 122.40006 90)
			(size 1.8034 0.508)
			(layers "F.Cu" "F.Mask" "F.Paste")
			(net "GND")
		)
		(pad "140" smd rect
			(at 0 123.249944 90)
			(size 1.8034 0.508)
			(layers "F.Cu" "F.Mask" "F.Paste")
			(net "GND")
		)
		(pad "141" smd rect
			(at 0 124.100082 90)
			(size 1.8034 0.508)
			(layers "F.Cu" "F.Mask" "F.Paste")
			(net "SMB_DDR_KLM_VPP_SCL")
		)
		(pad "142" smd rect
			(at 0 124.949966 90)
			(size 1.8034 0.508)
			(layers "F.Cu" "F.Mask" "F.Paste")
			(net "PVPP_KLM")
		)
		(pad "143" smd rect
			(at 0 125.800104 90)
			(size 1.8034 0.508)
			(layers "F.Cu" "F.Mask" "F.Paste")
			(net "PVPP_KLM")
		)
		(pad "144" smd rect
			(at 0 126.649988 90)
			(size 1.8034 0.508)
			(layers "F.Cu" "F.Mask" "F.Paste")
			(net "TP_CH_M_DIMM_M0_RFU_2")
		)
		(pad "145" smd rect
			(at 4.59994 0 90)
			(size 1.8034 0.508)
			(layers "F.Cu" "F.Mask" "F.Paste")
			(net "P12V_NVDIMM_KLM")
		)
		(pad "146" smd rect
			(at 4.59994 0.849884 90)
			(size 1.8034 0.508)
			(layers "F.Cu" "F.Mask" "F.Paste")
			(net "M_M_VREF")
		)
		(pad "147" smd rect
			(at 4.59994 1.700022 90)
			(size 1.8034 0.508)
			(layers "F.Cu" "F.Mask" "F.Paste")
			(net "GND")
		)
		(pad "148" smd rect
			(at 4.59994 2.549906 90)
			(size 1.8034 0.508)
			(layers "F.Cu" "F.Mask" "F.Paste")
			(net "M_M_DQ<4>")
		)
		(pad "149" smd rect
			(at 4.59994 3.400044 90)
			(size 1.8034 0.508)
			(layers "F.Cu" "F.Mask" "F.Paste")
			(net "GND")
		)
		(pad "150" smd rect
			(at 4.59994 4.249928 90)
			(size 1.8034 0.508)
			(layers "F.Cu" "F.Mask" "F.Paste")
			(net "M_M_DQ<0>")
		)
		(pad "151" smd rect
			(at 4.59994 5.100066 90)
			(size 1.8034 0.508)
			(layers "F.Cu" "F.Mask" "F.Paste")
			(net "GND")
		)
		(pad "152" smd rect
			(at 4.59994 5.94995 90)
			(size 1.8034 0.508)
			(layers "F.Cu" "F.Mask" "F.Paste")
			(net "M_M_DQS_DN<0>")
		)
		(pad "153" smd rect
			(at 4.59994 6.800088 90)
			(size 1.8034 0.508)
			(layers "F.Cu" "F.Mask" "F.Paste")
			(net "M_M_DQS_DP<0>")
		)
		(pad "154" smd rect
			(at 4.59994 7.649972 90)
			(size 1.8034 0.508)
			(layers "F.Cu" "F.Mask" "F.Paste")
			(net "GND")
		)
		(pad "155" smd rect
			(at 4.59994 8.50011 90)
			(size 1.8034 0.508)
			(layers "F.Cu" "F.Mask" "F.Paste")
			(net "M_M_DQ<6>")
		)
		(pad "156" smd rect
			(at 4.59994 9.349994 90)
			(size 1.8034 0.508)
			(layers "F.Cu" "F.Mask" "F.Paste")
			(net "GND")
		)
		(pad "157" smd rect
			(at 4.59994 10.199878 90)
			(size 1.8034 0.508)
			(layers "F.Cu" "F.Mask" "F.Paste")
			(net "M_M_DQ<2>")
		)
		(pad "158" smd rect
			(at 4.59994 11.050016 90)
			(size 1.8034 0.508)
			(layers "F.Cu" "F.Mask" "F.Paste")
			(net "GND")
		)
		(pad "159" smd rect
			(at 4.59994 11.8999 90)
			(size 1.8034 0.508)
			(layers "F.Cu" "F.Mask" "F.Paste")
			(net "M_M_DQ<12>")
		)
		(pad "160" smd rect
			(at 4.59994 12.750038 90)
			(size 1.8034 0.508)
			(layers "F.Cu" "F.Mask" "F.Paste")
			(net "GND")
		)
		(pad "161" smd rect
			(at 4.59994 13.599922 90)
			(size 1.8034 0.508)
			(layers "F.Cu" "F.Mask" "F.Paste")
			(net "M_M_DQ<8>")
		)
		(pad "162" smd rect
			(at 4.59994 14.45006 90)
			(size 1.8034 0.508)
			(layers "F.Cu" "F.Mask" "F.Paste")
			(net "GND")
		)
		(pad "163" smd rect
			(at 4.59994 15.299944 90)
			(size 1.8034 0.508)
			(layers "F.Cu" "F.Mask" "F.Paste")
			(net "M_M_DQS_DN<1>")
		)
		(pad "164" smd rect
			(at 4.59994 16.150082 90)
			(size 1.8034 0.508)
			(layers "F.Cu" "F.Mask" "F.Paste")
			(net "M_M_DQS_DP<1>")
		)
		(pad "165" smd rect
			(at 4.59994 16.999966 90)
			(size 1.8034 0.508)
			(layers "F.Cu" "F.Mask" "F.Paste")
			(net "GND")
		)
		(pad "166" smd rect
			(at 4.59994 17.850104 90)
			(size 1.8034 0.508)
			(layers "F.Cu" "F.Mask" "F.Paste")
			(net "M_M_DQ<14>")
		)
		(pad "167" smd rect
			(at 4.59994 18.699988 90)
			(size 1.8034 0.508)
			(layers "F.Cu" "F.Mask" "F.Paste")
			(net "GND")
		)
		(pad "168" smd rect
			(at 4.59994 19.550126 90)
			(size 1.8034 0.508)
			(layers "F.Cu" "F.Mask" "F.Paste")
			(net "M_M_DQ<10>")
		)
		(pad "169" smd rect
			(at 4.59994 20.40001 90)
			(size 1.8034 0.508)
			(layers "F.Cu" "F.Mask" "F.Paste")
			(net "GND")
		)
		(pad "170" smd rect
			(at 4.59994 21.249894 90)
			(size 1.8034 0.508)
			(layers "F.Cu" "F.Mask" "F.Paste")
			(net "M_M_DQ<20>")
		)
		(pad "171" smd rect
			(at 4.59994 22.100032 90)
			(size 1.8034 0.508)
			(layers "F.Cu" "F.Mask" "F.Paste")
			(net "GND")
		)
		(pad "172" smd rect
			(at 4.59994 22.949916 90)
			(size 1.8034 0.508)
			(layers "F.Cu" "F.Mask" "F.Paste")
			(net "M_M_DQ<16>")
		)
		(pad "173" smd rect
			(at 4.59994 23.800054 90)
			(size 1.8034 0.508)
			(layers "F.Cu" "F.Mask" "F.Paste")
			(net "GND")
		)
		(pad "174" smd rect
			(at 4.59994 24.649938 90)
			(size 1.8034 0.508)
			(layers "F.Cu" "F.Mask" "F.Paste")
			(net "M_M_DQS_DN<2>")
		)
		(pad "175" smd rect
			(at 4.59994 25.500076 90)
			(size 1.8034 0.508)
			(layers "F.Cu" "F.Mask" "F.Paste")
			(net "M_M_DQS_DP<2>")
		)
		(pad "176" smd rect
			(at 4.59994 26.34996 90)
			(size 1.8034 0.508)
			(layers "F.Cu" "F.Mask" "F.Paste")
			(net "GND")
		)
		(pad "177" smd rect
			(at 4.59994 27.200098 90)
			(size 1.8034 0.508)
			(layers "F.Cu" "F.Mask" "F.Paste")
			(net "M_M_DQ<22>")
		)
		(pad "178" smd rect
			(at 4.59994 28.049982 90)
			(size 1.8034 0.508)
			(layers "F.Cu" "F.Mask" "F.Paste")
			(net "GND")
		)
		(pad "179" smd rect
			(at 4.59994 28.90012 90)
			(size 1.8034 0.508)
			(layers "F.Cu" "F.Mask" "F.Paste")
			(net "M_M_DQ<18>")
		)
		(pad "180" smd rect
			(at 4.59994 29.750004 90)
			(size 1.8034 0.508)
			(layers "F.Cu" "F.Mask" "F.Paste")
			(net "GND")
		)
		(pad "181" smd rect
			(at 4.59994 30.599888 90)
			(size 1.8034 0.508)
			(layers "F.Cu" "F.Mask" "F.Paste")
			(net "M_M_DQ<28>")
		)
		(pad "182" smd rect
			(at 4.59994 31.450026 90)
			(size 1.8034 0.508)
			(layers "F.Cu" "F.Mask" "F.Paste")
			(net "GND")
		)
		(pad "183" smd rect
			(at 4.59994 32.29991 90)
			(size 1.8034 0.508)
			(layers "F.Cu" "F.Mask" "F.Paste")
			(net "M_M_DQ<24>")
		)
		(pad "184" smd rect
			(at 4.59994 33.150048 90)
			(size 1.8034 0.508)
			(layers "F.Cu" "F.Mask" "F.Paste")
			(net "GND")
		)
		(pad "185" smd rect
			(at 4.59994 33.999932 90)
			(size 1.8034 0.508)
			(layers "F.Cu" "F.Mask" "F.Paste")
			(net "M_M_DQS_DN<3>")
		)
		(pad "186" smd rect
			(at 4.59994 34.85007 90)
			(size 1.8034 0.508)
			(layers "F.Cu" "F.Mask" "F.Paste")
			(net "M_M_DQS_DP<3>")
		)
		(pad "187" smd rect
			(at 4.59994 35.699954 90)
			(size 1.8034 0.508)
			(layers "F.Cu" "F.Mask" "F.Paste")
			(net "GND")
		)
		(pad "188" smd rect
			(at 4.59994 36.550092 90)
			(size 1.8034 0.508)
			(layers "F.Cu" "F.Mask" "F.Paste")
			(net "M_M_DQ<30>")
		)
		(pad "189" smd rect
			(at 4.59994 37.399976 90)
			(size 1.8034 0.508)
			(layers "F.Cu" "F.Mask" "F.Paste")
			(net "GND")
		)
		(pad "190" smd rect
			(at 4.59994 38.250114 90)
			(size 1.8034 0.508)
			(layers "F.Cu" "F.Mask" "F.Paste")
			(net "M_M_DQ<26>")
		)
		(pad "191" smd rect
			(at 4.59994 39.099998 90)
			(size 1.8034 0.508)
			(layers "F.Cu" "F.Mask" "F.Paste")
			(net "GND")
		)
		(pad "192" smd rect
			(at 4.59994 39.949882 90)
			(size 1.8034 0.508)
			(layers "F.Cu" "F.Mask" "F.Paste")
			(net "M_M_ECC<4>")
		)
		(pad "193" smd rect
			(at 4.59994 40.80002 90)
			(size 1.8034 0.508)
			(layers "F.Cu" "F.Mask" "F.Paste")
			(net "GND")
		)
		(pad "194" smd rect
			(at 4.59994 41.649904 90)
			(size 1.8034 0.508)
			(layers "F.Cu" "F.Mask" "F.Paste")
			(net "M_M_ECC<0>")
		)
		(pad "195" smd rect
			(at 4.59994 42.500042 90)
			(size 1.8034 0.508)
			(layers "F.Cu" "F.Mask" "F.Paste")
			(net "GND")
		)
		(pad "196" smd rect
			(at 4.59994 43.349926 90)
			(size 1.8034 0.508)
			(layers "F.Cu" "F.Mask" "F.Paste")
			(net "M_M_DQS_DN<8>")
		)
		(pad "197" smd rect
			(at 4.59994 44.200064 90)
			(size 1.8034 0.508)
			(layers "F.Cu" "F.Mask" "F.Paste")
			(net "M_M_DQS_DP<8>")
		)
		(pad "198" smd rect
			(at 4.59994 45.049948 90)
			(size 1.8034 0.508)
			(layers "F.Cu" "F.Mask" "F.Paste")
			(net "GND")
		)
		(pad "199" smd rect
			(at 4.59994 45.900086 90)
			(size 1.8034 0.508)
			(layers "F.Cu" "F.Mask" "F.Paste")
			(net "M_M_ECC<6>")
		)
		(pad "200" smd rect
			(at 4.59994 46.74997 90)
			(size 1.8034 0.508)
			(layers "F.Cu" "F.Mask" "F.Paste")
			(net "GND")
		)
		(pad "201" smd rect
			(at 4.59994 47.600108 90)
			(size 1.8034 0.508)
			(layers "F.Cu" "F.Mask" "F.Paste")
			(net "M_M_ECC<2>")
		)
		(pad "202" smd rect
			(at 4.59994 48.449992 90)
			(size 1.8034 0.508)
			(layers "F.Cu" "F.Mask" "F.Paste")
			(net "GND")
		)
		(pad "203" smd rect
			(at 4.59994 49.299876 90)
			(size 1.8034 0.508)
			(layers "F.Cu" "F.Mask" "F.Paste")
			(net "M_M_CKE<1>")
		)
		(pad "204" smd rect
			(at 4.59994 50.150014 90)
			(size 1.8034 0.508)
			(layers "F.Cu" "F.Mask" "F.Paste")
			(net "PVDDQ_KLM")
		)
		(pad "205" smd rect
			(at 4.59994 50.999898 90)
			(size 1.8034 0.508)
			(layers "F.Cu" "F.Mask" "F.Paste")
			(net "TP_CH_M_DIMM_M0_RFU_0")
		)
		(pad "206" smd rect
			(at 4.59994 51.850036 90)
			(size 1.8034 0.508)
			(layers "F.Cu" "F.Mask" "F.Paste")
			(net "PVDDQ_KLM")
		)
		(pad "207" smd rect
			(at 4.59994 52.69992 90)
			(size 1.8034 0.508)
			(layers "F.Cu" "F.Mask" "F.Paste")
			(net "M_M_BG<1>")
		)
		(pad "208" smd rect
			(at 4.59994 53.550058 90)
			(size 1.8034 0.508)
			(layers "F.Cu" "F.Mask" "F.Paste")
			(net "M_M_ALERT_N")
		)
		(pad "209" smd rect
			(at 4.59994 54.399942 90)
			(size 1.8034 0.508)
			(layers "F.Cu" "F.Mask" "F.Paste")
			(net "PVDDQ_KLM")
		)
		(pad "210" smd rect
			(at 4.59994 55.25008 90)
			(size 1.8034 0.508)
			(layers "F.Cu" "F.Mask" "F.Paste")
			(net "M_M_MA<11>")
		)
		(pad "211" smd rect
			(at 4.59994 56.099964 90)
			(size 1.8034 0.508)
			(layers "F.Cu" "F.Mask" "F.Paste")
			(net "M_M_MA<7>")
		)
		(pad "212" smd rect
			(at 4.59994 56.950102 90)
			(size 1.8034 0.508)
			(layers "F.Cu" "F.Mask" "F.Paste")
			(net "PVDDQ_KLM")
		)
		(pad "213" smd rect
			(at 4.59994 57.799986 90)
			(size 1.8034 0.508)
			(layers "F.Cu" "F.Mask" "F.Paste")
			(net "M_M_MA<5>")
		)
		(pad "214" smd rect
			(at 4.59994 58.650124 90)
			(size 1.8034 0.508)
			(layers "F.Cu" "F.Mask" "F.Paste")
			(net "M_M_MA<4>")
		)
		(pad "215" smd rect
			(at 4.59994 59.500008 90)
			(size 1.8034 0.508)
			(layers "F.Cu" "F.Mask" "F.Paste")
			(net "PVDDQ_KLM")
		)
		(pad "216" smd rect
			(at 4.59994 60.349892 90)
			(size 1.8034 0.508)
			(layers "F.Cu" "F.Mask" "F.Paste")
			(net "M_M_MA<2>")
		)
		(pad "217" smd rect
			(at 4.59994 61.20003 90)
			(size 1.8034 0.508)
			(layers "F.Cu" "F.Mask" "F.Paste")
			(net "PVDDQ_KLM")
		)
		(pad "218" smd rect
			(at 4.59994 62.049914 90)
			(size 1.8034 0.508)
			(layers "F.Cu" "F.Mask" "F.Paste")
			(net "M_M_CLK_DP<1>")
		)
		(pad "219" smd rect
			(at 4.59994 62.900052 90)
			(size 1.8034 0.508)
			(layers "F.Cu" "F.Mask" "F.Paste")
			(net "M_M_CLK_DN<1>")
		)
		(pad "220" smd rect
			(at 4.59994 63.749936 90)
			(size 1.8034 0.508)
			(layers "F.Cu" "F.Mask" "F.Paste")
			(net "PVDDQ_KLM")
		)
		(pad "221" smd rect
			(at 4.59994 64.600074 90)
			(size 1.8034 0.508)
			(layers "F.Cu" "F.Mask" "F.Paste")
			(net "PVTT_KLM")
		)
		(pad "222" smd rect
			(at 4.59994 70.550024 90)
			(size 1.8034 0.508)
			(layers "F.Cu" "F.Mask" "F.Paste")
			(net "M_M_PAR")
		)
		(pad "223" smd rect
			(at 4.59994 71.399908 90)
			(size 1.8034 0.508)
			(layers "F.Cu" "F.Mask" "F.Paste")
			(net "PVDDQ_KLM")
		)
		(pad "224" smd rect
			(at 4.59994 72.250046 90)
			(size 1.8034 0.508)
			(layers "F.Cu" "F.Mask" "F.Paste")
			(net "M_M_BA<1>")
		)
		(pad "225" smd rect
			(at 4.59994 73.09993 90)
			(size 1.8034 0.508)
			(layers "F.Cu" "F.Mask" "F.Paste")
			(net "M_M_MA<10>")
		)
		(pad "226" smd rect
			(at 4.59994 73.950068 90)
			(size 1.8034 0.508)
			(layers "F.Cu" "F.Mask" "F.Paste")
			(net "PVDDQ_KLM")
		)
		(pad "227" smd rect
			(at 4.59994 74.799952 90)
			(size 1.8034 0.508)
			(layers "F.Cu" "F.Mask" "F.Paste")
			(net "TP_CH_M_DIMM_M0_RFU_1")
		)
		(pad "228" smd rect
			(at 4.59994 75.65009 90)
			(size 1.8034 0.508)
			(layers "F.Cu" "F.Mask" "F.Paste")
			(net "M_M_MA<14>")
		)
		(pad "229" smd rect
			(at 4.59994 76.499974 90)
			(size 1.8034 0.508)
			(layers "F.Cu" "F.Mask" "F.Paste")
			(net "PVDDQ_KLM")
		)
		(pad "230" smd rect
			(at 4.59994 77.350112 90)
			(size 1.8034 0.508)
			(layers "F.Cu" "F.Mask" "F.Paste")
			(net "FM_ADR_COMPLETE_KLM_N")
		)
		(pad "231" smd rect
			(at 4.59994 78.199996 90)
			(size 1.8034 0.508)
			(layers "F.Cu" "F.Mask" "F.Paste")
			(net "PVDDQ_KLM")
		)
		(pad "232" smd rect
			(at 4.59994 79.04988 90)
			(size 1.8034 0.508)
			(layers "F.Cu" "F.Mask" "F.Paste")
			(net "M_M_MA<13>")
		)
		(pad "233" smd rect
			(at 4.59994 79.900018 90)
			(size 1.8034 0.508)
			(layers "F.Cu" "F.Mask" "F.Paste")
			(net "PVDDQ_KLM")
		)
		(pad "234" smd rect
			(at 4.59994 80.749902 90)
			(size 1.8034 0.508)
			(layers "F.Cu" "F.Mask" "F.Paste")
			(net "M_M_MA<17>")
		)
		(pad "235" smd rect
			(at 4.59994 81.60004 90)
			(size 1.8034 0.508)
			(layers "F.Cu" "F.Mask" "F.Paste")
			(net "M_M_C<2>")
		)
		(pad "236" smd rect
			(at 4.59994 82.449924 90)
			(size 1.8034 0.508)
			(layers "F.Cu" "F.Mask" "F.Paste")
			(net "PVDDQ_KLM")
		)
		(pad "237" smd rect
			(at 4.59994 83.300062 90)
			(size 1.8034 0.508)
			(layers "F.Cu" "F.Mask" "F.Paste")
			(net "M_M_CS_N<3>")
		)
		(pad "238" smd rect
			(at 4.59994 84.149946 90)
			(size 1.8034 0.508)
			(layers "F.Cu" "F.Mask" "F.Paste")
			(net "PVPP_KLM")
		)
		(pad "239" smd rect
			(at 4.59994 85.000084 90)
			(size 1.8034 0.508)
			(layers "F.Cu" "F.Mask" "F.Paste")
			(net "GND")
		)
		(pad "240" smd rect
			(at 4.59994 85.849968 90)
			(size 1.8034 0.508)
			(layers "F.Cu" "F.Mask" "F.Paste")
			(net "M_M_DQ<36>")
		)
	)
)
